(kicad_pcb
	(version 20260206)
	(generator "pcbnew")
	(generator_version "10.0")
	(general
		(thickness 1.6)
		(legacy_teardrops no)
	)
	(paper "A4")
	(title_block
		(title "15969-1a.1015WZS0858.brd")
		(comment 1 "Tioga Pass / footprints 82-88 of 295")
	)
	(layers
		(0 "F.Cu" signal "TOP")
		(4 "In1.Cu" signal "L2GND")
		(6 "In2.Cu" signal "L3")
		(8 "In3.Cu" signal "L4")
		(10 "In4.Cu" signal "L5GND")
		(2 "B.Cu" signal "BOTTOM")
		(9 "F.Adhes" user "F.Adhesive")
		(11 "B.Adhes" user "B.Adhesive")
		(13 "F.Paste" user "Package Geometry/Pastemask Top")
		(15 "B.Paste" user "Package Geometry/Pastemask Bottom")
		(5 "F.SilkS" user "Ref Des/Silkscreen Top")
		(7 "B.SilkS" user "Ref Des/Silkscreen Bottom")
		(1 "F.Mask" user "Board Geometry/Soldermask Top")
		(3 "B.Mask" user "Board Geometry/Soldermask Bottom")
		(17 "Dwgs.User" user "User.Drawings")
		(19 "Cmts.User" user "User.Comments")
		(21 "Eco1.User" user "User.Eco1")
		(23 "Eco2.User" user "User.Eco2")
		(25 "Edge.Cuts" user "Board Geometry/Outline")
		(27 "Margin" user)
		(31 "F.CrtYd" user "Package Geometry/Place Bound Top")
		(29 "B.CrtYd" user "Package Geometry/Place Bound Bottom")
		(35 "F.Fab" user "Ref Des/Assembly Top")
		(33 "B.Fab" user "Ref Des/Assembly Bottom")
	)
	(footprint ""
		(layer "F.Cu")
		(at 132.207 -5.715 -90)
		(property "Reference" "R153"
			(at 0 0 270)
			(layer "F.SilkS")
			(hide yes)
			(effects
				(font
					(size 1.27 1.27)
				)
			)
		)
		(property "Value" "10KR2F-2-GP"
			(at 0.064008 -3.993896 270)
			(unlocked yes)
			(layer "F.Fab")
			(hide yes)
			(effects
				(font
					(size 1.016 1.016)
					(thickness 0.1524)
				)
			)
		)
		(property "Device Type" "R402H16"
			(at 0.064008 -5.517896 270)
			(unlocked yes)
			(layer "F.Fab")
			(hide yes)
			(effects
				(font
					(size 1.016 1.016)
					(thickness 0.1524)
				)
			)
		)
		(duplicate_pad_numbers_are_jumpers no)
		(fp_line
			(start -0.508 -0.9398)
			(end -0.508 0.9398)
			(stroke
				(width 0.1524)
				(type default)
			)
			(layer "F.SilkS")
		)
		(fp_line
			(start 0.508 -0.9398)
			(end -0.508 -0.9398)
			(stroke
				(width 0.1524)
				(type default)
			)
			(layer "F.SilkS")
		)
		(fp_rect
			(start -0.508 0.9398)
			(end 0.508 -0.9398)
			(stroke
				(width 0)
				(type default)
			)
			(fill no)
			(layer "F.CrtYd")
		)
		(fp_rect
			(start -0.508 0.9398)
			(end 0.508 -0.9398)
			(stroke
				(width 0)
				(type default)
			)
			(fill no)
			(layer "F.Fab")
		)
		(pad "1" smd custom
			(at 0 -0.4445 270)
			(size 0.1397 0.1397)
			(layers "F.Cu" "F.Mask" "F.Paste")
			(net "P3V3_STBY")
			(options
				(clearance outline)
				(anchor circle)
			)
			(primitives
				(gr_poly
					(pts
						(arc
							(start -0.1778 -0.2794)
							(mid -0.249642 -0.249642)
							(end -0.2794 -0.1778)
						)
						(arc
							(start -0.2794 0.1778)
							(mid -0.249642 0.249642)
							(end -0.1778 0.2794)
						)
						(arc
							(start 0.1778 0.2794)
							(mid 0.249642 0.249642)
							(end 0.2794 0.1778)
						)
						(arc
							(start 0.2794 -0.1778)
							(mid 0.249642 -0.249642)
							(end 0.1778 -0.2794)
						)
					)
					(width 0)
					(fill yes)
				)
			)
		)
		(pad "2" smd custom
			(at 0 0.4445 270)
			(size 0.1397 0.1397)
			(layers "F.Cu" "F.Mask" "F.Paste")
			(net "GPIO_P_EXP_A2")
			(options
				(clearance outline)
				(anchor circle)
			)
			(primitives
				(gr_poly
					(pts
						(arc
							(start -0.1778 -0.2794)
							(mid -0.249642 -0.249642)
							(end -0.2794 -0.1778)
						)
						(arc
							(start -0.2794 0.1778)
							(mid -0.249642 0.249642)
							(end -0.1778 0.2794)
						)
						(arc
							(start 0.1778 0.2794)
							(mid 0.249642 0.249642)
							(end 0.2794 0.1778)
						)
						(arc
							(start 0.2794 -0.1778)
							(mid 0.249642 -0.249642)
							(end 0.1778 -0.2794)
						)
					)
					(width 0)
					(fill yes)
				)
			)
		)
	)
	(footprint ""
		(layer "F.Cu")
		(at 35.052 -23.622 90)
		(property "Reference" "C22"
			(at 0 0 90)
			(layer "F.SilkS")
			(hide yes)
			(effects
				(font
					(size 1.27 1.27)
				)
			)
		)
		(property "Value" "SCD1U16V2KX-3GP"
			(at 1.1811 -2.7051 90)
			(unlocked yes)
			(layer "F.Fab")
			(hide yes)
			(effects
				(font
					(size 1.016 1.016)
					(thickness 0.1524)
				)
			)
		)
		(property "Device Type" "C402H22"
			(at 1.1811 -4.2291 90)
			(unlocked yes)
			(layer "F.Fab")
			(hide yes)
			(effects
				(font
					(size 1.016 1.016)
					(thickness 0.1524)
				)
			)
		)
		(duplicate_pad_numbers_are_jumpers no)
		(fp_rect
			(start -0.4318 0.9525)
			(end 0.4318 -0.9525)
			(stroke
				(width 0)
				(type default)
			)
			(fill no)
			(layer "F.CrtYd")
		)
		(fp_rect
			(start -0.4318 0.9525)
			(end 0.4318 -0.9525)
			(stroke
				(width 0)
				(type default)
			)
			(fill no)
			(layer "F.Fab")
		)
		(pad "1" smd custom
			(at 0 -0.4445 90)
			(size 0.1524 0.1524)
			(layers "F.Cu" "F.Mask" "F.Paste")
			(net "P3V3")
			(options
				(clearance outline)
				(anchor circle)
			)
			(primitives
				(gr_poly
					(pts
						(arc
							(start 0.3048 -0.2032)
							(mid 0.275042 -0.275042)
							(end 0.2032 -0.3048)
						)
						(arc
							(start -0.2032 -0.3048)
							(mid -0.275042 -0.275042)
							(end -0.3048 -0.2032)
						)
						(arc
							(start -0.3048 0.2032)
							(mid -0.275042 0.275042)
							(end -0.2032 0.3048)
						)
						(arc
							(start 0.2032 0.3048)
							(mid 0.275042 0.275042)
							(end 0.3048 0.2032)
						)
					)
					(width 0)
					(fill yes)
				)
			)
		)
		(pad "2" smd custom
			(at 0 0.4445 90)
			(size 0.1524 0.1524)
			(layers "F.Cu" "F.Mask" "F.Paste")
			(net "GND")
			(options
				(clearance outline)
				(anchor circle)
			)
			(primitives
				(gr_poly
					(pts
						(arc
							(start 0.3048 -0.2032)
							(mid 0.275042 -0.275042)
							(end 0.2032 -0.3048)
						)
						(arc
							(start -0.2032 -0.3048)
							(mid -0.275042 -0.275042)
							(end -0.3048 -0.2032)
						)
						(arc
							(start -0.3048 0.2032)
							(mid -0.275042 0.275042)
							(end -0.2032 0.3048)
						)
						(arc
							(start 0.2032 0.3048)
							(mid 0.275042 0.275042)
							(end 0.3048 0.2032)
						)
					)
					(width 0)
					(fill yes)
				)
			)
		)
	)
	(footprint ""
		(layer "F.Cu")
		(at 131.6736 -17.78 -90)
		(property "Reference" "R128"
			(at 0 0 270)
			(layer "F.SilkS")
			(hide yes)
			(effects
				(font
					(size 1.27 1.27)
				)
			)
		)
		(property "Value" "10KR2F-2-GP"
			(at 0.064008 -3.993896 270)
			(unlocked yes)
			(layer "F.Fab")
			(hide yes)
			(effects
				(font
					(size 1.016 1.016)
					(thickness 0.1524)
				)
			)
		)
		(property "Device Type" "R402H16"
			(at 0.064008 -5.517896 270)
			(unlocked yes)
			(layer "F.Fab")
			(hide yes)
			(effects
				(font
					(size 1.016 1.016)
					(thickness 0.1524)
				)
			)
		)
		(duplicate_pad_numbers_are_jumpers no)
		(fp_line
			(start -0.508 -0.9398)
			(end -0.508 0.9398)
			(stroke
				(width 0.1524)
				(type default)
			)
			(layer "F.SilkS")
		)
		(fp_line
			(start 0.508 -0.9398)
			(end -0.508 -0.9398)
			(stroke
				(width 0.1524)
				(type default)
			)
			(layer "F.SilkS")
		)
		(fp_rect
			(start -0.508 0.9398)
			(end 0.508 -0.9398)
			(stroke
				(width 0)
				(type default)
			)
			(fill no)
			(layer "F.CrtYd")
		)
		(fp_rect
			(start -0.508 0.9398)
			(end 0.508 -0.9398)
			(stroke
				(width 0)
				(type default)
			)
			(fill no)
			(layer "F.Fab")
		)
		(pad "1" smd custom
			(at 0 -0.4445 270)
			(size 0.1397 0.1397)
			(layers "F.Cu" "F.Mask" "F.Paste")
			(net "P3V3_STBY")
			(options
				(clearance outline)
				(anchor circle)
			)
			(primitives
				(gr_poly
					(pts
						(arc
							(start -0.1778 -0.2794)
							(mid -0.249642 -0.249642)
							(end -0.2794 -0.1778)
						)
						(arc
							(start -0.2794 0.1778)
							(mid -0.249642 0.249642)
							(end -0.1778 0.2794)
						)
						(arc
							(start 0.1778 0.2794)
							(mid 0.249642 0.249642)
							(end 0.2794 0.1778)
						)
						(arc
							(start 0.2794 -0.1778)
							(mid 0.249642 -0.249642)
							(end 0.1778 -0.2794)
						)
					)
					(width 0)
					(fill yes)
				)
			)
		)
		(pad "2" smd custom
			(at 0 0.4445 270)
			(size 0.1397 0.1397)
			(layers "F.Cu" "F.Mask" "F.Paste")
			(net "GPIO_B_IO1_6")
			(options
				(clearance outline)
				(anchor circle)
			)
			(primitives
				(gr_poly
					(pts
						(arc
							(start -0.1778 -0.2794)
							(mid -0.249642 -0.249642)
							(end -0.2794 -0.1778)
						)
						(arc
							(start -0.2794 0.1778)
							(mid -0.249642 0.249642)
							(end -0.1778 0.2794)
						)
						(arc
							(start 0.1778 0.2794)
							(mid 0.249642 0.249642)
							(end 0.2794 0.1778)
						)
						(arc
							(start 0.2794 -0.1778)
							(mid 0.249642 -0.249642)
							(end 0.1778 -0.2794)
						)
					)
					(width 0)
					(fill yes)
				)
			)
		)
	)
	(footprint ""
		(layer "F.Cu")
		(at 131.699 -16.7386 90)
		(property "Reference" "R129"
			(at 0 0 90)
			(layer "F.SilkS")
			(hide yes)
			(effects
				(font
					(size 1.27 1.27)
				)
			)
		)
		(property "Value" "10KR2F-2-GP"
			(at 0.064008 -3.993896 90)
			(unlocked yes)
			(layer "F.Fab")
			(hide yes)
			(effects
				(font
					(size 1.016 1.016)
					(thickness 0.1524)
				)
			)
		)
		(property "Device Type" "R402H16"
			(at 0.064008 -5.517896 90)
			(unlocked yes)
			(layer "F.Fab")
			(hide yes)
			(effects
				(font
					(size 1.016 1.016)
					(thickness 0.1524)
				)
			)
		)
		(duplicate_pad_numbers_are_jumpers no)
		(fp_line
			(start 0.508 -0.9398)
			(end -0.508 -0.9398)
			(stroke
				(width 0.1524)
				(type default)
			)
			(layer "F.SilkS")
		)
		(fp_line
			(start -0.508 -0.9398)
			(end -0.508 0.9398)
			(stroke
				(width 0.1524)
				(type default)
			)
			(layer "F.SilkS")
		)
		(fp_rect
			(start -0.508 0.9398)
			(end 0.508 -0.9398)
			(stroke
				(width 0)
				(type default)
			)
			(fill no)
			(layer "F.CrtYd")
		)
		(fp_rect
			(start -0.508 0.9398)
			(end 0.508 -0.9398)
			(stroke
				(width 0)
				(type default)
			)
			(fill no)
			(layer "F.Fab")
		)
		(pad "1" smd custom
			(at 0 -0.4445 90)
			(size 0.1397 0.1397)
			(layers "F.Cu" "F.Mask" "F.Paste")
			(net "GPIO_B_IO1_6")
			(options
				(clearance outline)
				(anchor circle)
			)
			(primitives
				(gr_poly
					(pts
						(arc
							(start -0.1778 -0.2794)
							(mid -0.249642 -0.249642)
							(end -0.2794 -0.1778)
						)
						(arc
							(start -0.2794 0.1778)
							(mid -0.249642 0.249642)
							(end -0.1778 0.2794)
						)
						(arc
							(start 0.1778 0.2794)
							(mid 0.249642 0.249642)
							(end 0.2794 0.1778)
						)
						(arc
							(start 0.2794 -0.1778)
							(mid 0.249642 -0.249642)
							(end 0.1778 -0.2794)
						)
					)
					(width 0)
					(fill yes)
				)
			)
		)
		(pad "2" smd custom
			(at 0 0.4445 90)
			(size 0.1397 0.1397)
			(layers "F.Cu" "F.Mask" "F.Paste")
			(net "GND")
			(options
				(clearance outline)
				(anchor circle)
			)
			(primitives
				(gr_poly
					(pts
						(arc
							(start -0.1778 -0.2794)
							(mid -0.249642 -0.249642)
							(end -0.2794 -0.1778)
						)
						(arc
							(start -0.2794 0.1778)
							(mid -0.249642 0.249642)
							(end -0.1778 0.2794)
						)
						(arc
							(start 0.1778 0.2794)
							(mid 0.249642 0.249642)
							(end 0.2794 0.1778)
						)
						(arc
							(start 0.2794 -0.1778)
							(mid 0.249642 -0.249642)
							(end 0.1778 -0.2794)
						)
					)
					(width 0)
					(fill yes)
				)
			)
		)
	)
	(footprint ""
		(layer "F.Cu")
		(at 127.4318 -1.016 -90)
		(property "Reference" "R152"
			(at 0 0 270)
			(layer "F.SilkS")
			(hide yes)
			(effects
				(font
					(size 1.27 1.27)
				)
			)
		)
		(property "Value" "10KR2F-2-GP"
			(at 0.064008 -3.993896 270)
			(unlocked yes)
			(layer "F.Fab")
			(hide yes)
			(effects
				(font
					(size 1.016 1.016)
					(thickness 0.1524)
				)
			)
		)
		(property "Device Type" "R402H16"
			(at 0.064008 -5.517896 270)
			(unlocked yes)
			(layer "F.Fab")
			(hide yes)
			(effects
				(font
					(size 1.016 1.016)
					(thickness 0.1524)
				)
			)
		)
		(duplicate_pad_numbers_are_jumpers no)
		(fp_line
			(start -0.508 -0.9398)
			(end -0.508 0.9398)
			(stroke
				(width 0.1524)
				(type default)
			)
			(layer "F.SilkS")
		)
		(fp_line
			(start 0.508 -0.9398)
			(end -0.508 -0.9398)
			(stroke
				(width 0.1524)
				(type default)
			)
			(layer "F.SilkS")
		)
		(fp_rect
			(start -0.508 0.9398)
			(end 0.508 -0.9398)
			(stroke
				(width 0)
				(type default)
			)
			(fill no)
			(layer "F.CrtYd")
		)
		(fp_rect
			(start -0.508 0.9398)
			(end 0.508 -0.9398)
			(stroke
				(width 0)
				(type default)
			)
			(fill no)
			(layer "F.Fab")
		)
		(pad "1" smd custom
			(at 0 -0.4445 270)
			(size 0.1397 0.1397)
			(layers "F.Cu" "F.Mask" "F.Paste")
			(net "GPIO_P_EXP_A0")
			(options
				(clearance outline)
				(anchor circle)
			)
			(primitives
				(gr_poly
					(pts
						(arc
							(start -0.1778 -0.2794)
							(mid -0.249642 -0.249642)
							(end -0.2794 -0.1778)
						)
						(arc
							(start -0.2794 0.1778)
							(mid -0.249642 0.249642)
							(end -0.1778 0.2794)
						)
						(arc
							(start 0.1778 0.2794)
							(mid 0.249642 0.249642)
							(end 0.2794 0.1778)
						)
						(arc
							(start 0.2794 -0.1778)
							(mid 0.249642 -0.249642)
							(end 0.1778 -0.2794)
						)
					)
					(width 0)
					(fill yes)
				)
			)
		)
		(pad "2" smd custom
			(at 0 0.4445 270)
			(size 0.1397 0.1397)
			(layers "F.Cu" "F.Mask" "F.Paste")
			(net "GND")
			(options
				(clearance outline)
				(anchor circle)
			)
			(primitives
				(gr_poly
					(pts
						(arc
							(start -0.1778 -0.2794)
							(mid -0.249642 -0.249642)
							(end -0.2794 -0.1778)
						)
						(arc
							(start -0.2794 0.1778)
							(mid -0.249642 0.249642)
							(end -0.1778 0.2794)
						)
						(arc
							(start 0.1778 0.2794)
							(mid 0.249642 0.249642)
							(end 0.2794 0.1778)
						)
						(arc
							(start 0.2794 -0.1778)
							(mid 0.249642 -0.249642)
							(end 0.1778 -0.2794)
						)
					)
					(width 0)
					(fill yes)
				)
			)
		)
	)
	(footprint ""
		(layer "F.Cu")
		(at 21.7424 4.826 90)
		(property "Reference" "R57"
			(at 0 0 90)
			(layer "F.SilkS")
			(hide yes)
			(effects
				(font
					(size 1.27 1.27)
				)
			)
		)
		(property "Value" "4K7R2F-GP"
			(at 0.064008 -3.993896 90)
			(unlocked yes)
			(layer "F.Fab")
			(hide yes)
			(effects
				(font
					(size 1.016 1.016)
					(thickness 0.1524)
				)
			)
		)
		(property "Device Type" "R402H16"
			(at 0.064008 -5.517896 90)
			(unlocked yes)
			(layer "F.Fab")
			(hide yes)
			(effects
				(font
					(size 1.016 1.016)
					(thickness 0.1524)
				)
			)
		)
		(duplicate_pad_numbers_are_jumpers no)
		(fp_line
			(start 0.508 -0.9398)
			(end -0.508 -0.9398)
			(stroke
				(width 0.1524)
				(type default)
			)
			(layer "F.SilkS")
		)
		(fp_line
			(start -0.508 -0.9398)
			(end -0.508 0.9398)
			(stroke
				(width 0.1524)
				(type default)
			)
			(layer "F.SilkS")
		)
		(fp_rect
			(start -0.508 0.9398)
			(end 0.508 -0.9398)
			(stroke
				(width 0)
				(type default)
			)
			(fill no)
			(layer "F.CrtYd")
		)
		(fp_rect
			(start -0.508 0.9398)
			(end 0.508 -0.9398)
			(stroke
				(width 0)
				(type default)
			)
			(fill no)
			(layer "F.Fab")
		)
		(pad "1" smd custom
			(at 0 -0.4445 90)
			(size 0.1397 0.1397)
			(layers "F.Cu" "F.Mask" "F.Paste")
			(net "P3V3_STBY")
			(options
				(clearance outline)
				(anchor circle)
			)
			(primitives
				(gr_poly
					(pts
						(arc
							(start -0.1778 -0.2794)
							(mid -0.249642 -0.249642)
							(end -0.2794 -0.1778)
						)
						(arc
							(start -0.2794 0.1778)
							(mid -0.249642 0.249642)
							(end -0.1778 0.2794)
						)
						(arc
							(start 0.1778 0.2794)
							(mid 0.249642 0.249642)
							(end 0.2794 0.1778)
						)
						(arc
							(start 0.2794 -0.1778)
							(mid 0.249642 -0.249642)
							(end 0.1778 -0.2794)
						)
					)
					(width 0)
					(fill yes)
				)
			)
		)
		(pad "2" smd custom
			(at 0 0.4445 90)
			(size 0.1397 0.1397)
			(layers "F.Cu" "F.Mask" "F.Paste")
			(net "FM_SLT_CFG1")
			(options
				(clearance outline)
				(anchor circle)
			)
			(primitives
				(gr_poly
					(pts
						(arc
							(start -0.1778 -0.2794)
							(mid -0.249642 -0.249642)
							(end -0.2794 -0.1778)
						)
						(arc
							(start -0.2794 0.1778)
							(mid -0.249642 0.249642)
							(end -0.1778 0.2794)
						)
						(arc
							(start 0.1778 0.2794)
							(mid 0.249642 0.249642)
							(end 0.2794 0.1778)
						)
						(arc
							(start 0.2794 -0.1778)
							(mid 0.249642 -0.249642)
							(end 0.1778 -0.2794)
						)
					)
					(width 0)
					(fill yes)
				)
			)
		)
	)
	(footprint ""
		(layer "F.Cu")
		(at 123.3424 -21.1074)
		(property "Reference" "R165"
			(at 0 0 0)
			(layer "F.SilkS")
			(hide yes)
			(effects
				(font
					(size 1.27 1.27)
				)
			)
		)
		(property "Value" "0R2F-1-GP"
			(at 0.064008 -3.993896 0)
			(unlocked yes)
			(layer "F.Fab")
			(hide yes)
			(effects
				(font
					(size 1.016 1.016)
					(thickness 0.1524)
				)
			)
		)
		(property "Device Type" "R402H16"
			(at 0.064008 -5.517896 0)
			(unlocked yes)
			(layer "F.Fab")
			(hide yes)
			(effects
				(font
					(size 1.016 1.016)
					(thickness 0.1524)
				)
			)
		)
		(duplicate_pad_numbers_are_jumpers no)
		(fp_line
			(start -0.508 -0.9398)
			(end -0.508 0.9398)
			(stroke
				(width 0.1524)
				(type default)
			)
			(layer "F.SilkS")
		)
		(fp_line
			(start 0.508 -0.9398)
			(end -0.508 -0.9398)
			(stroke
				(width 0.1524)
				(type default)
			)
			(layer "F.SilkS")
		)
		(fp_rect
			(start -0.508 0.9398)
			(end 0.508 -0.9398)
			(stroke
				(width 0)
				(type default)
			)
			(fill no)
			(layer "F.CrtYd")
		)
		(fp_rect
			(start -0.508 0.9398)
			(end 0.508 -0.9398)
			(stroke
				(width 0)
				(type default)
			)
			(fill no)
			(layer "F.Fab")
		)
		(pad "1" smd custom
			(at 0 -0.4445)
			(size 0.1397 0.1397)
			(layers "F.Cu" "F.Mask" "F.Paste")
			(net "SMB_BMC_DEVICE_ALERT_N")
			(options
				(clearance outline)
				(anchor circle)
			)
			(primitives
				(gr_poly
					(pts
						(arc
							(start -0.1778 -0.2794)
							(mid -0.249642 -0.249642)
							(end -0.2794 -0.1778)
						)
						(arc
							(start -0.2794 0.1778)
							(mid -0.249642 0.249642)
							(end -0.1778 0.2794)
						)
						(arc
							(start 0.1778 0.2794)
							(mid 0.249642 0.249642)
							(end 0.2794 0.1778)
						)
						(arc
							(start 0.2794 -0.1778)
							(mid 0.249642 -0.249642)
							(end 0.1778 -0.2794)
						)
					)
					(width 0)
					(fill yes)
				)
			)
		)
		(pad "2" smd custom
			(at 0 0.4445)
			(size 0.1397 0.1397)
			(layers "F.Cu" "F.Mask" "F.Paste")
			(net "GPIO_B_EXP_INT_N")
			(options
				(clearance outline)
				(anchor circle)
			)
			(primitives
				(gr_poly
					(pts
						(arc
							(start -0.1778 -0.2794)
							(mid -0.249642 -0.249642)
							(end -0.2794 -0.1778)
						)
						(arc
							(start -0.2794 0.1778)
							(mid -0.249642 0.249642)
							(end -0.1778 0.2794)
						)
						(arc
							(start 0.1778 0.2794)
							(mid 0.249642 0.249642)
							(end 0.2794 0.1778)
						)
						(arc
							(start 0.2794 -0.1778)
							(mid 0.249642 -0.249642)
							(end 0.1778 -0.2794)
						)
					)
					(width 0)
					(fill yes)
				)
			)
		)
	)
)
